FILE_TYPE = CONNECTIVITY;
{Allegro Design Entry HDL 17.2-2016 S081 (4005846) 1/11/2022}
"PAGE_NUMBER" = 24;
0"NC";
1"P5E_CPU0_P0_TX_DN<15:0>";
2"P5E_CPU0_P0_TX_DP<15:0>";
3"P5E_CPU0_P0_RX_DN<15:0>";
4"P5E_CPU0_P0_RX_DP<15:0>";
5"P5E_CPU0_P1_TX_DN<15:0>";
6"P5E_CPU0_P1_TX_DP<15:0>";
7"P5E_CPU0_P1_RX_DN<15:0>";
8"P5E_CPU0_P1_RX_DP<15:0>";
9"P5E_CPU0_P1_TX_DN<1>";
10"P5E_CPU0_P1_TX_DN<2>";
11"P5E_CPU0_P1_TX_DN<10>";
12"P5E_CPU0_P1_TX_DN<11>";
13"P5E_CPU0_P1_TX_DP<12>";
14"P5E_CPU0_P1_TX_DN<12>";
15"P5E_CPU0_P1_TX_DP<13>";
16"P5E_CPU0_P1_TX_DN<14>";
17"P5E_CPU0_P1_TX_DN<0>";
18"P5E_CPU0_P1_TX_DP<1>";
19"P5E_CPU0_P1_TX_DP<0>";
20"P5E_CPU0_P1_RX_DP<1>";
21"P5E_CPU0_P1_RX_DN<0>";
22"P5E_CPU0_P1_RX_DP<0>";
23"P5E_CPU0_P0_TX_DN<0>";
24"P5E_CPU0_P0_TX_DP<1>";
25"P5E_CPU0_P0_TX_DP<0>";
26"P5E_CPU0_P0_TX_DN<9>";
27"P5E_CPU0_P0_TX_DP<10>";
28"P5E_CPU0_P0_TX_DP<9>";
29"P5E_CPU0_P0_TX_DN<8>";
30"P5E_CPU0_P0_TX_DP<8>";
31"P5E_CPU0_P0_TX_DN<7>";
32"P5E_CPU0_P0_TX_DN<6>";
33"P5E_CPU0_P0_TX_DN<5>";
34"P5E_CPU0_P0_TX_DN<3>";
35"P5E_CPU0_P0_TX_DP<5>";
36"P5E_CPU0_P0_TX_DP<6>";
37"P5E_CPU0_P0_TX_DP<7>";
38"P5E_CPU0_P0_TX_DN<11>";
39"P5E_CPU0_P0_TX_DP<13>";
40"P5E_CPU0_P0_TX_DN<14>";
41"P5E_CPU0_P0_TX_DN<10>";
42"P5E_CPU0_P0_TX_DP<11>";
43"P5E_CPU0_P1_TX_DP<4>";
44"P5E_CPU0_P1_TX_DN<4>";
45"P5E_CPU0_P1_TX_DN<3>";
46"P5E_CPU0_P1_RX_DN<5>";
47"P5E_CPU0_P1_RX_DN<4>";
48"P5E_CPU0_P1_RX_DN<3>";
49"P5E_CPU0_P0_TX_DN<1>";
50"P5E_CPU0_P1_RX_DN<14>";
51"P5E_CPU0_P1_RX_DN<15>";
52"P5E_CPU0_P1_RX_DP<14>";
53"P5E_CPU0_P1_RX_DN<12>";
54"P5E_CPU0_P1_RX_DN<11>";
55"P5E_CPU0_P1_RX_DN<10>";
56"P5E_CPU0_P1_RX_DN<9>";
57"P5E_CPU0_P1_RX_DN<8>";
58"P5E_CPU0_P1_RX_DP<12>";
59"P5E_CPU0_P1_RX_DP<13>";
60"P5E_CPU0_P1_RX_DP<11>";
61"P5E_CPU0_P1_RX_DP<10>";
62"P5E_CPU0_P1_RX_DP<9>";
63"P5E_CPU0_P1_RX_DP<8>";
64"P5E_CPU0_P1_RX_DN<7>";
65"P5E_CPU0_P1_RX_DN<6>";
66"P5E_CPU0_P1_RX_DP<7>";
67"P5E_CPU0_P1_RX_DP<6>";
68"P5E_CPU0_P1_RX_DP<5>";
69"P5E_CPU0_P1_RX_DP<4>";
70"P5E_CPU0_P1_RX_DP<3>";
71"P5E_CPU0_P1_RX_DN<1>";
72"P5E_CPU0_P1_RX_DN<2>";
73"P5E_CPU0_P1_RX_DP<2>";
74"P5E_CPU0_P1_RX_DP<15>";
75"P5E_CPU0_P1_RX_DN<13>";
76"P5E_CPU0_P1_TX_DP<15>";
77"P5E_CPU0_P1_TX_DP<14>";
78"P5E_CPU0_P1_TX_DN<15>";
79"P5E_CPU0_P1_TX_DN<13>";
80"P5E_CPU0_P1_TX_DP<11>";
81"P5E_CPU0_P1_TX_DP<8>";
82"P5E_CPU0_P1_TX_DP<9>";
83"P5E_CPU0_P1_TX_DP<10>";
84"P5E_CPU0_P1_TX_DN<9>";
85"P5E_CPU0_P1_TX_DN<8>";
86"P5E_CPU0_P1_TX_DP<6>";
87"P5E_CPU0_P1_TX_DP<7>";
88"P5E_CPU0_P1_TX_DP<3>";
89"P5E_CPU0_P1_TX_DP<5>";
90"P5E_CPU0_P1_TX_DN<7>";
91"P5E_CPU0_P1_TX_DN<6>";
92"P5E_CPU0_P0_RX_DP<11>";
93"P5E_CPU0_P0_RX_DN<11>";
94"P5E_CPU0_P0_RX_DP<13>";
95"P5E_CPU0_P0_RX_DN<9>";
96"P5E_CPU0_P0_RX_DN<10>";
97"P5E_CPU0_P0_RX_DN<12>";
98"P5E_CPU0_P0_RX_DP<8>";
99"P5E_CPU0_P0_RX_DP<14>";
100"P5E_CPU0_P0_RX_DP<6>";
101"P5E_CPU0_P0_RX_DN<5>";
102"P5E_CPU0_P0_RX_DP<5>";
103"P5E_CPU0_P0_TX_DN<4>";
104"P5E_CPU0_P0_RX_DN<7>";
105"P5E_CPU0_P0_RX_DN<4>";
106"P5E_CPU0_P0_RX_DP<4>";
107"P5E_CPU0_P0_RX_DP<7>";
108"P5E_CPU0_P0_RX_DN<6>";
109"P5E_CPU0_P0_RX_DP<10>";
110"P5E_CPU0_P0_RX_DP<12>";
111"P5E_CPU0_P0_RX_DN<13>";
112"P5E_CPU0_P0_RX_DP<15>";
113"P5E_CPU0_P0_RX_DN<15>";
114"P5E_CPU0_P0_RX_DP<2>";
115"P5E_CPU0_P0_RX_DN<2>";
116"P5E_CPU0_P0_RX_DP<3>";
117"P5E_CPU0_P0_RX_DN<3>";
118"P5E_CPU0_P0_RX_DP<0>";
119"P5E_CPU0_P0_RX_DN<14>";
120"P5E_CPU0_P0_RX_DN<1>";
121"P5E_CPU0_P0_RX_DP<1>";
122"P5E_CPU0_P0_RX_DN<0>";
123"P5E_CPU0_P0_TX_DP<2>";
124"P5E_CPU0_P1_TX_DP<2>";
125"P5E_CPU0_P0_TX_DP<4>";
126"P5E_CPU0_P0_TX_DP<3>";
127"P5E_CPU0_P1_TX_DN<5>";
128"P5E_CPU0_P0_TX_DP<12>";
129"P5E_CPU0_P0_TX_DN<15>";
130"P5E_CPU0_P0_TX_DP<15>";
131"P5E_CPU0_P0_RX_DP<9>";
132"P5E_CPU0_P0_RX_DN<8>";
133"P5E_CPU0_P0_TX_DP<14>";
134"P5E_CPU0_P0_TX_DN<13>";
135"P5E_CPU0_P0_TX_DN<2>";
136"P5E_CPU0_P0_TX_DN<12>";
%"GENOA_SP5"
"15","(-4925,5000)","0","pure_quanta","I148";
;
LOCATION"U25"
$SEC"15"
CDS_SEC"15"
VALUE"SOCKET6096_13568-001"
MATERIAL"IO"
PART_TYPE"SMLF"
PART_NUMBER"DGA^6000030"
CDS_LIB"pure_quanta"
NEEDS_NO_SIZE"TRUE"
CDS_LMAN_SYM_OUTLINE"-1100,950,1100,-950";
"P0_RXP11||SATA13_RXP"
$PN"BU43"92;
"P0_TXP12||SATA14_TXP"
$PN"CN44"128;
"P0_TXP15||SATA17_TXP"
$PN"CM41"130;
"P0_RXN11||SATA13_RXN"
$PN"BU44"93;
"P0_RXN14||SATA16_RXN"
$PN"BV41"119;
"P0_TXN15||SATA17_TXN"
$PN"CM40"129;
"P0_RXP13||SATA15_RXP"
$PN"CB40"94;
"P0_TXN9||SATA11_TXN"
$PN"CN46"26;
"P0_TXN12||SATA14_TXN"
$PN"CN43"136;
"P0_RXP10||SATA12_RXP"
$PN"CA43"109;
"P0_RXN9||SATA11_RXN"
$PN"BW44"95;
"P0_TXP11||SATA13_TXP"
$PN"CU44"42;
"P0_TXP14||SATA16_TXP"
$PN"CP41"133;
"P0_RXN10||SATA12_RXN"
$PN"CA44"96;
"P0_RXN13||SATA15_RXN"
$PN"CB41"111;
"P0_TXP9||SATA11_TXP"
$PN"CN47"28;
"P0_RXP9||SATA11_RXP"
$PN"BW43"131;
"P0_TXN14||SATA16_TXN"
$PN"CP40"40;
"P0_RXP12||SATA14_RXP"
$PN"BY40"110;
"P0_RXP15||SATA17_RXP"
$PN"BT40"112;
"P0_TXN8||SATA10_TXN"
$PN"CU46"29;
"P0_TXN11||SATA13_TXN"
$PN"CU43"38;
"P0_RXN8||SATA10_RXN"
$PN"BU47"132;
"P0_TXP13||SATA15_TXP"
$PN"CT41"39;
"P0_TXP10||SATA12_TXP"
$PN"CR44"27;
"P0_RXN15||SATA17_RXN"
$PN"BT41"113;
"P0_TXP8||SATA10_TXP"
$PN"CU47"30;
"P0_RXN12||SATA14_RXN"
$PN"BY41"97;
"P0_RXP8||SATA10_RXP"
$PN"BU46"98;
"P0_RXP14||SATA16_RXP"
$PN"BV40"99;
"P0_TXN10||SATA12_TXN"
$PN"CR43"41;
"P0_TXN13||SATA15_TXN"
$PN"CT40"134;
"P0_TXP3||SATA03_TXP"
$PN"CN50"126;
"P0_TXP6||SATA06_TXP"
$PN"CL50"36;
"P0_TXP0||SATA00_TXP"
$PN"CN53"25;
"P0_RXP3||SATA03_RXP"
$PN"BW49"116;
"P0_RXP6||SATA06_RXP"
$PN"BW46"100;
"P0_TXN5||SATA05_TXN"
$PN"CU49"33;
"P0_RXP0||SATA00_RXP"
$PN"BW52"118;
"P0_TXN2||SATA02_TXN"
$PN"CL52"135;
"P0_RXN2||SATA02_RXN"
$PN"BU53"115;
"P0_RXN5||SATA05_RXN"
$PN"BU50"101;
"P0_TXP2||SATA02_TXP"
$PN"CL53"123;
"P0_TXP5||SATA05_TXP"
$PN"CU50"35;
"P0_RXP5||SATA05_RXP"
$PN"BU49"102;
"P0_RXP2||SATA02_RXP"
$PN"BU52"114;
"P0_TXN1||SATA01_TXN"
$PN"CR52"49;
"P0_TXN7||SATA07_TXN"
$PN"CR46"31;
"P0_TXN4||SATA04_TXN"
$PN"CR49"103;
"P0_RXN7||SATA07_RXN"
$PN"CA47"104;
"P0_RXN1||SATA01_RXN"
$PN"CA53"120;
"P0_RXN4||SATA04_RXN"
$PN"CA50"105;
"P0_TXP7||SATA07_TXP"
$PN"CR47"37;
"P0_TXP1||SATA01_TXP"
$PN"CR53"24;
"P0_TXP4||SATA04_TXP"
$PN"CR50"125;
"P0_RXP4||SATA04_RXP"
$PN"CA49"106;
"P0_RXP7||SATA07_RXP"
$PN"CA46"107;
"P0_TXN6||SATA06_TXN"
$PN"CL49"32;
"P0_RXP1||SATA01_RXP"
$PN"CA52"121;
"P0_TXN0||SATA00_TXN"
$PN"CN52"23;
"P0_TXN3||SATA03_TXN"
$PN"CN49"34;
"P0_RXN3||SATA03_RXN"
$PN"BW50"117;
"P0_RXN6||SATA06_RXN"
$PN"BW47"108;
"P0_RXN0||SATA00_RXN"
$PN"BW53"122;
%"GENOA_SP5"
"16","(-5000,1525)","0","pure_quanta","I149";
;
LOCATION"U25"
$SEC"16"
CDS_SEC"16"
PART_NUMBER"DGA^6000030"
PART_TYPE"SMLF"
MATERIAL"IO"
VALUE"SOCKET6096_13568-001"
CDS_LMAN_SYM_OUTLINE"-1100,950,1100,-950"
NEEDS_NO_SIZE"TRUE"
CDS_LIB"pure_quanta";
"P1_RXN6"
$PN"CE47"65;
"P1_RXN5"
$PN"CC50"46;
"P1_RXP7"
$PN"CG46"66;
"P1_TXN7"
$PN"DA46"90;
"P1_RXN4"
$PN"CG50"47;
"P1_RXP6"
$PN"CE46"67;
"P1_TXN6"
$PN"CW49"91;
"P1_RXN3"
$PN"CE50"48;
"P1_RXP5"
$PN"CC49"68;
"P1_TXN5"
$PN"DC49"127;
"P1_TXP7"
$PN"DA47"87;
"P1_RXN2"
$PN"CC53"72;
"P1_RXP4"
$PN"CG49"69;
"P1_TXN4"
$PN"DA49"44;
"P1_TXP6"
$PN"CW50"86;
"P1_RXN1"
$PN"CG53"71;
"P1_RXP3"
$PN"CE49"70;
"P1_TXN3"
$PN"CW52"45;
"P1_TXP5"
$PN"DC50"89;
"P1_RXN0"
$PN"CE53"21;
"P1_RXP2"
$PN"CC52"73;
"P1_TXN2"
$PN"DC52"10;
"P1_TXP4"
$PN"DA50"43;
"P1_RXP1"
$PN"CG52"20;
"P1_TXN1"
$PN"DA52"9;
"P1_TXP3"
$PN"CW53"88;
"P1_RXP0"
$PN"CE52"22;
"P1_TXN0"
$PN"CU52"17;
"P1_TXP2"
$PN"DC53"124;
"P1_TXP1"
$PN"DA53"18;
"P1_TXP0"
$PN"CU53"19;
"P1_RXN7"
$PN"CG47"64;
"P1_TXN15"
$PN"CV40"78;
"P1_TXP15"
$PN"CV41"76;
"P1_TXN14"
$PN"CY40"16;
"P1_TXP14"
$PN"CY41"77;
"P1_TXN13"
$PN"DB40"79;
"P1_TXP13"
$PN"DB41"15;
"P1_TXN12"
$PN"CW43"14;
"P1_TXP12"
$PN"CW44"13;
"P1_TXN11"
$PN"DC43"12;
"P1_TXP11"
$PN"DC44"80;
"P1_TXN10"
$PN"DA43"11;
"P1_TXP10"
$PN"DA44"83;
"P1_TXN9"
$PN"CW46"84;
"P1_TXP9"
$PN"CW47"82;
"P1_TXN8"
$PN"DC46"85;
"P1_TXP8"
$PN"DC47"81;
"P1_RXN15"
$PN"CD41"51;
"P1_RXP15"
$PN"CD40"74;
"P1_RXN14"
$PN"CF41"50;
"P1_RXP14"
$PN"CF40"52;
"P1_RXN13"
$PN"CH41"75;
"P1_RXP13"
$PN"CH40"59;
"P1_RXN12"
$PN"CC44"53;
"P1_RXP12"
$PN"CC43"58;
"P1_RXN11"
$PN"CJ44"54;
"P1_RXP11"
$PN"CJ43"60;
"P1_RXN10"
$PN"CG44"55;
"P1_RXP10"
$PN"CG43"61;
"P1_RXN9"
$PN"CE44"56;
"P1_RXP9"
$PN"CE43"62;
"P1_RXN8"
$PN"CC47"57;
"P1_RXP8"
$PN"CC46"63;
%"TAP"
"6","(-3175,2275)","2","mstr_standard","I220";
;
ROOM"RISER1"
HDL_TAP"TRUE"
BODY_TYPE"PLUMBING"
CDS_LIB"mstr_standard"
BOM_COST"IO_SLOT";
"B \NAC \NWC"5;
"S \NAC"
BN"0"17;
%"TAP"
"6","(-3175,2175)","2","mstr_standard","I221";
;
ROOM"RISER1"
HDL_TAP"TRUE"
BODY_TYPE"PLUMBING"
BOM_COST"IO_SLOT"
CDS_LIB"mstr_standard";
"B \NAC \NWC"5;
"S \NAC"
BN"1"9;
%"TAP"
"6","(-3325,2225)","2","mstr_standard","I222";
;
ROOM"RISER1"
HDL_TAP"TRUE"
BODY_TYPE"PLUMBING"
BOM_COST"IO_SLOT"
CDS_LIB"mstr_standard";
"B \NAC \NWC"6;
"S \NAC"
BN"1"18;
%"TAP"
"6","(-3325,2325)","2","mstr_standard","I223";
;
ROOM"RISER1"
HDL_TAP"TRUE"
BODY_TYPE"PLUMBING"
BOM_COST"IO_SLOT"
CDS_LIB"mstr_standard";
"B \NAC \NWC"6;
"S \NAC"
BN"0"19;
%"TAP"
"6","(-3325,2125)","2","standard","I224";
;
ROOM"RISER1"
HDL_TAP"TRUE"
BODY_TYPE"PLUMBING"
BOM_COST"IO_SLOT"
CDS_LIB"standard";
"B \NAC \NWC"6;
"S \NAC"
BN"2"124;
%"TAP"
"6","(-3175,2075)","2","standard","I225";
;
ROOM"RISER1"
HDL_TAP"TRUE"
BODY_TYPE"PLUMBING"
BOM_COST"IO_SLOT"
CDS_LIB"standard";
"B \NAC \NWC"5;
"S \NAC"
BN"2"10;
%"TAP"
"6","(-3175,1875)","2","standard","I226";
;
ROOM"RISER1"
HDL_TAP"TRUE"
BODY_TYPE"PLUMBING"
BOM_COST"IO_SLOT"
CDS_LIB"standard";
"B \NAC \NWC"5;
"S \NAC"
BN"4"44;
%"TAP"
"6","(-3175,1975)","2","standard","I227";
;
ROOM"RISER1"
HDL_TAP"TRUE"
BODY_TYPE"PLUMBING"
BOM_COST"IO_SLOT"
CDS_LIB"standard";
"B \NAC \NWC"5;
"S \NAC"
BN"3"45;
%"TAP"
"6","(-3325,2025)","2","standard","I228";
;
ROOM"RISER1"
HDL_TAP"TRUE"
BODY_TYPE"PLUMBING"
BOM_COST"IO_SLOT"
CDS_LIB"standard";
"B \NAC \NWC"6;
"S \NAC"
BN"3"88;
%"TAP"
"6","(-3325,1925)","2","standard","I229";
;
ROOM"RISER1"
HDL_TAP"TRUE"
BODY_TYPE"PLUMBING"
BOM_COST"IO_SLOT"
CDS_LIB"standard";
"B \NAC \NWC"6;
"S \NAC"
BN"4"43;
%"TAP"
"6","(-3175,1775)","2","standard","I230";
;
ROOM"RISER1"
HDL_TAP"TRUE"
BODY_TYPE"PLUMBING"
BOM_COST"IO_SLOT"
CDS_LIB"standard";
"B \NAC \NWC"5;
"S \NAC"
BN"5"127;
%"TAP"
"6","(-3175,1675)","2","standard","I231";
;
ROOM"RISER1"
HDL_TAP"TRUE"
BODY_TYPE"PLUMBING"
BOM_COST"IO_SLOT"
CDS_LIB"standard";
"B \NAC \NWC"5;
"S \NAC"
BN"6"91;
%"TAP"
"6","(-3325,1725)","2","standard","I232";
;
ROOM"RISER1"
HDL_TAP"TRUE"
BODY_TYPE"PLUMBING"
BOM_COST"IO_SLOT"
CDS_LIB"standard";
"B \NAC \NWC"6;
"S \NAC"
BN"6"86;
%"TAP"
"6","(-3325,1825)","2","standard","I233";
;
ROOM"RISER1"
HDL_TAP"TRUE"
BODY_TYPE"PLUMBING"
BOM_COST"IO_SLOT"
CDS_LIB"standard";
"B \NAC \NWC"6;
"S \NAC"
BN"5"89;
%"TAP"
"6","(-3325,1625)","2","standard","I234";
;
ROOM"RISER1"
HDL_TAP"TRUE"
BODY_TYPE"PLUMBING"
BOM_COST"IO_SLOT"
CDS_LIB"standard";
"B \NAC \NWC"6;
"S \NAC"
BN"7"87;
%"TAP"
"6","(-3175,1575)","2","standard","I235";
;
ROOM"RISER1"
HDL_TAP"TRUE"
BODY_TYPE"PLUMBING"
BOM_COST"IO_SLOT"
CDS_LIB"standard";
"B \NAC \NWC"5;
"S \NAC"
BN"7"90;
%"TAP"
"6","(-3175,1375)","2","standard","I236";
;
ROOM"RISER1"
HDL_TAP"TRUE"
BODY_TYPE"PLUMBING"
BOM_COST"IO_SLOT"
CDS_LIB"standard";
"B \NAC \NWC"5;
"S \NAC"
BN"9"84;
%"TAP"
"6","(-3175,1475)","2","standard","I237";
;
ROOM"RISER1"
HDL_TAP"TRUE"
BODY_TYPE"PLUMBING"
BOM_COST"IO_SLOT"
CDS_LIB"standard";
"B \NAC \NWC"5;
"S \NAC"
BN"8"85;
%"TAP"
"6","(-3325,1525)","2","standard","I238";
;
ROOM"RISER1"
HDL_TAP"TRUE"
BODY_TYPE"PLUMBING"
BOM_COST"IO_SLOT"
CDS_LIB"standard";
"B \NAC \NWC"6;
"S \NAC"
BN"8"81;
%"TAP"
"6","(-3325,1425)","2","standard","I239";
;
ROOM"RISER1"
HDL_TAP"TRUE"
BODY_TYPE"PLUMBING"
BOM_COST"IO_SLOT"
CDS_LIB"standard";
"B \NAC \NWC"6;
"S \NAC"
BN"9"82;
%"TAP"
"6","(-3175,1275)","2","standard","I240";
;
ROOM"RISER1"
HDL_TAP"TRUE"
BODY_TYPE"PLUMBING"
BOM_COST"IO_SLOT"
CDS_LIB"standard";
"B \NAC \NWC"5;
"S \NAC"
BN"10"11;
%"TAP"
"6","(-3175,1175)","2","standard","I241";
;
ROOM"RISER1"
HDL_TAP"TRUE"
BODY_TYPE"PLUMBING"
BOM_COST"IO_SLOT"
CDS_LIB"standard";
"B \NAC \NWC"5;
"S \NAC"
BN"11"12;
%"TAP"
"6","(-3325,1125)","2","standard","I242";
;
ROOM"RISER1"
HDL_TAP"TRUE"
BODY_TYPE"PLUMBING"
BOM_COST"IO_SLOT"
CDS_LIB"standard";
"B \NAC \NWC"6;
"S \NAC"
BN"12"13;
%"TAP"
"6","(-3325,1225)","2","standard","I243";
;
ROOM"RISER1"
HDL_TAP"TRUE"
BODY_TYPE"PLUMBING"
BOM_COST"IO_SLOT"
CDS_LIB"standard";
"B \NAC \NWC"6;
"S \NAC"
BN"11"80;
%"TAP"
"6","(-3325,1325)","2","standard","I244";
;
ROOM"RISER1"
HDL_TAP"TRUE"
BODY_TYPE"PLUMBING"
BOM_COST"IO_SLOT"
CDS_LIB"standard";
"B \NAC \NWC"6;
"S \NAC"
BN"10"83;
%"TAP"
"6","(-3175,975)","2","standard","I245";
;
ROOM"RISER1"
HDL_TAP"TRUE"
BODY_TYPE"PLUMBING"
BOM_COST"IO_SLOT"
CDS_LIB"standard";
"B \NAC \NWC"5;
"S \NAC"
BN"13"79;
%"TAP"
"6","(-3175,1075)","2","standard","I246";
;
ROOM"RISER1"
HDL_TAP"TRUE"
BODY_TYPE"PLUMBING"
BOM_COST"IO_SLOT"
CDS_LIB"standard";
"B \NAC \NWC"5;
"S \NAC"
BN"12"14;
%"TAP"
"6","(-3175,875)","2","standard","I247";
;
ROOM"RISER1"
HDL_TAP"TRUE"
BODY_TYPE"PLUMBING"
BOM_COST"IO_SLOT"
CDS_LIB"standard";
"B \NAC \NWC"5;
"S \NAC"
BN"14"16;
%"TAP"
"6","(-3325,1025)","2","standard","I248";
;
ROOM"RISER1"
HDL_TAP"TRUE"
BODY_TYPE"PLUMBING"
BOM_COST"IO_SLOT"
CDS_LIB"standard";
"B \NAC \NWC"6;
"S \NAC"
BN"13"15;
%"TAP"
"6","(-3325,925)","2","standard","I249";
;
ROOM"RISER1"
HDL_TAP"TRUE"
BODY_TYPE"PLUMBING"
BOM_COST"IO_SLOT"
CDS_LIB"standard";
"B \NAC \NWC"6;
"S \NAC"
BN"14"77;
%"TAP"
"6","(-3325,825)","2","standard","I250";
;
ROOM"RISER1"
HDL_TAP"TRUE"
BODY_TYPE"PLUMBING"
BOM_COST"IO_SLOT"
CDS_LIB"standard";
"B \NAC \NWC"6;
"S \NAC"
BN"15"76;
%"TAP"
"6","(-3175,775)","2","standard","I251";
;
ROOM"RISER1"
HDL_TAP"TRUE"
BODY_TYPE"PLUMBING"
BOM_COST"IO_SLOT"
CDS_LIB"standard";
"B \NAC \NWC"5;
"S \NAC"
BN"15"78;
%"TAP"
"6","(-6900,775)","0","standard","I292";
;
HDL_TAP"TRUE"
BODY_TYPE"PLUMBING"
CDS_LIB"standard";
"B \NAC \NWC"7;
"S \NAC"
BN"15"51;
%"TAP"
"6","(-6900,875)","0","standard","I293";
;
HDL_TAP"TRUE"
BODY_TYPE"PLUMBING"
CDS_LIB"standard";
"B \NAC \NWC"7;
"S \NAC"
BN"14"50;
%"TAP"
"6","(-6750,825)","0","standard","I294";
;
HDL_TAP"TRUE"
BODY_TYPE"PLUMBING"
CDS_LIB"standard";
"B \NAC \NWC"8;
"S \NAC"
BN"15"74;
%"TAP"
"6","(-6750,925)","0","standard","I295";
;
HDL_TAP"TRUE"
BODY_TYPE"PLUMBING"
CDS_LIB"standard";
"B \NAC \NWC"8;
"S \NAC"
BN"14"52;
%"TAP"
"6","(-6900,1075)","0","standard","I296";
;
HDL_TAP"TRUE"
BODY_TYPE"PLUMBING"
CDS_LIB"standard";
"B \NAC \NWC"7;
"S \NAC"
BN"12"53;
%"TAP"
"6","(-6900,975)","0","standard","I297";
;
HDL_TAP"TRUE"
BODY_TYPE"PLUMBING"
CDS_LIB"standard";
"B \NAC \NWC"7;
"S \NAC"
BN"13"75;
%"TAP"
"6","(-6900,1175)","0","standard","I298";
;
HDL_TAP"TRUE"
BODY_TYPE"PLUMBING"
CDS_LIB"standard";
"B \NAC \NWC"7;
"S \NAC"
BN"11"54;
%"TAP"
"6","(-6750,1025)","0","standard","I299";
;
HDL_TAP"TRUE"
BODY_TYPE"PLUMBING"
CDS_LIB"standard";
"B \NAC \NWC"8;
"S \NAC"
BN"13"59;
%"TAP"
"6","(-6750,1125)","0","standard","I300";
;
HDL_TAP"TRUE"
BODY_TYPE"PLUMBING"
CDS_LIB"standard";
"B \NAC \NWC"8;
"S \NAC"
BN"12"58;
%"TAP"
"6","(-6900,1275)","0","standard","I301";
;
HDL_TAP"TRUE"
BODY_TYPE"PLUMBING"
CDS_LIB"standard";
"B \NAC \NWC"7;
"S \NAC"
BN"10"55;
%"TAP"
"6","(-6900,1375)","0","standard","I302";
;
HDL_TAP"TRUE"
BODY_TYPE"PLUMBING"
CDS_LIB"standard";
"B \NAC \NWC"7;
"S \NAC"
BN"9"56;
%"TAP"
"6","(-6750,1225)","0","standard","I303";
;
HDL_TAP"TRUE"
BODY_TYPE"PLUMBING"
CDS_LIB"standard";
"B \NAC \NWC"8;
"S \NAC"
BN"11"60;
%"TAP"
"6","(-6750,1325)","0","standard","I304";
;
HDL_TAP"TRUE"
BODY_TYPE"PLUMBING"
CDS_LIB"standard";
"B \NAC \NWC"8;
"S \NAC"
BN"10"61;
%"TAP"
"6","(-6750,1425)","0","standard","I305";
;
HDL_TAP"TRUE"
BODY_TYPE"PLUMBING"
CDS_LIB"standard";
"B \NAC \NWC"8;
"S \NAC"
BN"9"62;
%"TAP"
"6","(-6900,1575)","0","standard","I308";
;
HDL_TAP"TRUE"
BODY_TYPE"PLUMBING"
CDS_LIB"standard";
"B \NAC \NWC"7;
"S \NAC"
BN"7"64;
%"TAP"
"6","(-6900,1475)","0","standard","I309";
;
HDL_TAP"TRUE"
BODY_TYPE"PLUMBING"
CDS_LIB"standard";
"B \NAC \NWC"7;
"S \NAC"
BN"8"57;
%"TAP"
"6","(-6900,1675)","0","standard","I310";
;
HDL_TAP"TRUE"
BODY_TYPE"PLUMBING"
CDS_LIB"standard";
"B \NAC \NWC"7;
"S \NAC"
BN"6"65;
%"TAP"
"6","(-6750,1525)","0","standard","I311";
;
HDL_TAP"TRUE"
BODY_TYPE"PLUMBING"
CDS_LIB"standard";
"B \NAC \NWC"8;
"S \NAC"
BN"8"63;
%"TAP"
"6","(-6750,1625)","0","standard","I312";
;
HDL_TAP"TRUE"
BODY_TYPE"PLUMBING"
CDS_LIB"standard";
"B \NAC \NWC"8;
"S \NAC"
BN"7"66;
%"TAP"
"6","(-6750,1725)","0","standard","I313";
;
HDL_TAP"TRUE"
BODY_TYPE"PLUMBING"
CDS_LIB"standard";
"B \NAC \NWC"8;
"S \NAC"
BN"6"67;
%"TAP"
"6","(-6900,1775)","0","standard","I314";
;
HDL_TAP"TRUE"
BODY_TYPE"PLUMBING"
CDS_LIB"standard";
"B \NAC \NWC"7;
"S \NAC"
BN"5"46;
%"TAP"
"6","(-6900,1975)","0","standard","I315";
;
HDL_TAP"TRUE"
BODY_TYPE"PLUMBING"
CDS_LIB"standard";
"B \NAC \NWC"7;
"S \NAC"
BN"3"48;
%"TAP"
"6","(-6900,1875)","0","standard","I316";
;
HDL_TAP"TRUE"
BODY_TYPE"PLUMBING"
CDS_LIB"standard";
"B \NAC \NWC"7;
"S \NAC"
BN"4"47;
%"TAP"
"6","(-6750,1825)","0","standard","I317";
;
HDL_TAP"TRUE"
BODY_TYPE"PLUMBING"
CDS_LIB"standard";
"B \NAC \NWC"8;
"S \NAC"
BN"5"68;
%"TAP"
"6","(-6750,1925)","0","standard","I318";
;
HDL_TAP"TRUE"
BODY_TYPE"PLUMBING"
CDS_LIB"standard";
"B \NAC \NWC"8;
"S \NAC"
BN"4"69;
%"TAP"
"6","(-6900,2075)","0","standard","I319";
;
HDL_TAP"TRUE"
BODY_TYPE"PLUMBING"
CDS_LIB"standard";
"B \NAC \NWC"7;
"S \NAC"
BN"2"72;
%"TAP"
"6","(-6900,2175)","0","mstr_standard","I320";
;
HDL_TAP"TRUE"
BODY_TYPE"PLUMBING"
CDS_LIB"mstr_standard";
"B \NAC \NWC"7;
"S \NAC"
BN"1"71;
%"TAP"
"6","(-6750,2025)","0","standard","I321";
;
HDL_TAP"TRUE"
BODY_TYPE"PLUMBING"
CDS_LIB"standard";
"B \NAC \NWC"8;
"S \NAC"
BN"3"70;
%"TAP"
"6","(-6750,2125)","0","mstr_standard","I322";
;
HDL_TAP"TRUE"
BODY_TYPE"PLUMBING"
CDS_LIB"mstr_standard";
"B \NAC \NWC"8;
"S \NAC"
BN"2"73;
%"TAP"
"6","(-6750,2225)","0","mstr_standard","I323";
;
HDL_TAP"TRUE"
BODY_TYPE"PLUMBING"
CDS_LIB"mstr_standard";
"B \NAC \NWC"8;
"S \NAC"
BN"1"20;
%"TAP"
"6","(-6900,2275)","0","mstr_standard","I324";
;
HDL_TAP"TRUE"
BODY_TYPE"PLUMBING"
CDS_LIB"mstr_standard";
"B \NAC \NWC"7;
"S \NAC"
BN"0"21;
%"TAP"
"6","(-6750,2325)","0","mstr_standard","I325";
;
HDL_TAP"TRUE"
BODY_TYPE"PLUMBING"
CDS_LIB"mstr_standard";
"B \NAC \NWC"8;
"S \NAC"
BN"0"22;
%"TAP"
"6","(-6825,4450)","0","standard","I326";
;
HDL_TAP"TRUE"
BODY_TYPE"PLUMBING"
CDS_LIB"standard";
"B \NAC \NWC"3;
"S \NAC"
BN"13"111;
%"TAP"
"6","(-6675,4300)","0","standard","I327";
;
HDL_TAP"TRUE"
BODY_TYPE"PLUMBING"
CDS_LIB"standard";
"B \NAC \NWC"4;
"S \NAC"
BN"15"112;
%"TAP"
"6","(-6675,5800)","0","mstr_standard","I328";
;
HDL_TAP"TRUE"
BODY_TYPE"PLUMBING"
CDS_LIB"mstr_standard";
"B \NAC \NWC"4;
"S \NAC"
BN"0"118;
%"TAP"
"6","(-6675,5700)","0","mstr_standard","I329";
;
HDL_TAP"TRUE"
BODY_TYPE"PLUMBING"
CDS_LIB"mstr_standard";
"B \NAC \NWC"4;
"S \NAC"
BN"1"121;
%"TAP"
"6","(-6675,5600)","0","mstr_standard","I330";
;
HDL_TAP"TRUE"
BODY_TYPE"PLUMBING"
CDS_LIB"mstr_standard";
"B \NAC \NWC"4;
"S \NAC"
BN"2"114;
%"TAP"
"6","(-6825,5550)","0","standard","I331";
;
HDL_TAP"TRUE"
BODY_TYPE"PLUMBING"
CDS_LIB"standard";
"B \NAC \NWC"3;
"S \NAC"
BN"2"115;
%"TAP"
"6","(-6825,5650)","0","mstr_standard","I332";
;
HDL_TAP"TRUE"
BODY_TYPE"PLUMBING"
CDS_LIB"mstr_standard";
"B \NAC \NWC"3;
"S \NAC"
BN"1"120;
%"TAP"
"6","(-6825,5750)","0","mstr_standard","I333";
;
HDL_TAP"TRUE"
BODY_TYPE"PLUMBING"
CDS_LIB"mstr_standard";
"B \NAC \NWC"3;
"S \NAC"
BN"0"122;
%"TAP"
"6","(-6675,5500)","0","standard","I334";
;
HDL_TAP"TRUE"
BODY_TYPE"PLUMBING"
CDS_LIB"standard";
"B \NAC \NWC"4;
"S \NAC"
BN"3"116;
%"TAP"
"6","(-6675,5400)","0","standard","I335";
;
HDL_TAP"TRUE"
BODY_TYPE"PLUMBING"
CDS_LIB"standard";
"B \NAC \NWC"4;
"S \NAC"
BN"4"106;
%"TAP"
"6","(-6675,5300)","0","standard","I336";
;
HDL_TAP"TRUE"
BODY_TYPE"PLUMBING"
CDS_LIB"standard";
"B \NAC \NWC"4;
"S \NAC"
BN"5"102;
%"TAP"
"6","(-6675,5200)","0","standard","I337";
;
HDL_TAP"TRUE"
BODY_TYPE"PLUMBING"
CDS_LIB"standard";
"B \NAC \NWC"4;
"S \NAC"
BN"6"100;
%"TAP"
"6","(-6675,5100)","0","standard","I338";
;
HDL_TAP"TRUE"
BODY_TYPE"PLUMBING"
CDS_LIB"standard";
"B \NAC \NWC"4;
"S \NAC"
BN"7"107;
%"TAP"
"6","(-6825,5350)","0","standard","I339";
;
HDL_TAP"TRUE"
BODY_TYPE"PLUMBING"
CDS_LIB"standard";
"B \NAC \NWC"3;
"S \NAC"
BN"4"105;
%"TAP"
"6","(-6825,5450)","0","standard","I340";
;
HDL_TAP"TRUE"
BODY_TYPE"PLUMBING"
CDS_LIB"standard";
"B \NAC \NWC"3;
"S \NAC"
BN"3"117;
%"TAP"
"6","(-6825,5250)","0","standard","I341";
;
HDL_TAP"TRUE"
BODY_TYPE"PLUMBING"
CDS_LIB"standard";
"B \NAC \NWC"3;
"S \NAC"
BN"5"101;
%"TAP"
"6","(-6825,5150)","0","standard","I342";
;
HDL_TAP"TRUE"
BODY_TYPE"PLUMBING"
CDS_LIB"standard";
"B \NAC \NWC"3;
"S \NAC"
BN"6"108;
%"TAP"
"6","(-6825,5050)","0","standard","I343";
;
HDL_TAP"TRUE"
BODY_TYPE"PLUMBING"
CDS_LIB"standard";
"B \NAC \NWC"3;
"S \NAC"
BN"7"104;
%"TAP"
"6","(-6675,5000)","0","standard","I344";
;
HDL_TAP"TRUE"
BODY_TYPE"PLUMBING"
CDS_LIB"standard";
"B \NAC \NWC"4;
"S \NAC"
BN"8"98;
%"TAP"
"6","(-6675,4900)","0","standard","I345";
;
HDL_TAP"TRUE"
BODY_TYPE"PLUMBING"
CDS_LIB"standard";
"B \NAC \NWC"4;
"S \NAC"
BN"9"131;
%"TAP"
"6","(-6675,4800)","0","standard","I346";
;
HDL_TAP"TRUE"
BODY_TYPE"PLUMBING"
CDS_LIB"standard";
"B \NAC \NWC"4;
"S \NAC"
BN"10"109;
%"TAP"
"6","(-6675,4700)","0","standard","I347";
;
HDL_TAP"TRUE"
BODY_TYPE"PLUMBING"
CDS_LIB"standard";
"B \NAC \NWC"4;
"S \NAC"
BN"11"92;
%"TAP"
"6","(-6675,4500)","0","standard","I348";
;
HDL_TAP"TRUE"
BODY_TYPE"PLUMBING"
CDS_LIB"standard";
"B \NAC \NWC"4;
"S \NAC"
BN"13"94;
%"TAP"
"6","(-6675,4600)","0","standard","I349";
;
HDL_TAP"TRUE"
BODY_TYPE"PLUMBING"
CDS_LIB"standard";
"B \NAC \NWC"4;
"S \NAC"
BN"12"110;
%"TAP"
"6","(-6825,4950)","0","standard","I350";
;
HDL_TAP"TRUE"
BODY_TYPE"PLUMBING"
CDS_LIB"standard";
"B \NAC \NWC"3;
"S \NAC"
BN"8"132;
%"TAP"
"6","(-6825,4850)","0","standard","I351";
;
HDL_TAP"TRUE"
BODY_TYPE"PLUMBING"
CDS_LIB"standard";
"B \NAC \NWC"3;
"S \NAC"
BN"9"95;
%"TAP"
"6","(-6825,4750)","0","standard","I352";
;
HDL_TAP"TRUE"
BODY_TYPE"PLUMBING"
CDS_LIB"standard";
"B \NAC \NWC"3;
"S \NAC"
BN"10"96;
%"TAP"
"6","(-6825,4650)","0","standard","I353";
;
HDL_TAP"TRUE"
BODY_TYPE"PLUMBING"
CDS_LIB"standard";
"B \NAC \NWC"3;
"S \NAC"
BN"11"93;
%"TAP"
"6","(-6825,4550)","0","standard","I354";
;
HDL_TAP"TRUE"
BODY_TYPE"PLUMBING"
CDS_LIB"standard";
"B \NAC \NWC"3;
"S \NAC"
BN"12"97;
%"TAP"
"6","(-6675,4400)","0","standard","I355";
;
HDL_TAP"TRUE"
BODY_TYPE"PLUMBING"
CDS_LIB"standard";
"B \NAC \NWC"4;
"S \NAC"
BN"14"99;
%"TAP"
"6","(-6825,4250)","0","standard","I356";
;
HDL_TAP"TRUE"
BODY_TYPE"PLUMBING"
CDS_LIB"standard";
"B \NAC \NWC"3;
"S \NAC"
BN"15"113;
%"TAP"
"6","(-6825,4350)","0","standard","I357";
;
HDL_TAP"TRUE"
BODY_TYPE"PLUMBING"
CDS_LIB"standard";
"B \NAC \NWC"3;
"S \NAC"
BN"14"119;
%"TAP"
"6","(-3100,5750)","2","mstr_standard","I360";
;
ROOM"RISER1"
HDL_TAP"TRUE"
BODY_TYPE"PLUMBING"
BOM_COST"IO_SLOT"
CDS_LIB"mstr_standard";
"B \NAC \NWC"1;
"S \NAC"
BN"0"23;
%"TAP"
"6","(-3100,5650)","2","mstr_standard","I361";
;
ROOM"RISER1"
HDL_TAP"TRUE"
BODY_TYPE"PLUMBING"
BOM_COST"IO_SLOT"
CDS_LIB"mstr_standard";
"B \NAC \NWC"1;
"S \NAC"
BN"1"49;
%"TAP"
"6","(-3100,5550)","2","standard","I362";
;
ROOM"RISER1"
HDL_TAP"TRUE"
BODY_TYPE"PLUMBING"
BOM_COST"IO_SLOT"
CDS_LIB"standard";
"B \NAC \NWC"1;
"S \NAC"
BN"2"135;
%"TAP"
"6","(-3250,5700)","2","mstr_standard","I363";
;
ROOM"RISER1"
HDL_TAP"TRUE"
BODY_TYPE"PLUMBING"
BOM_COST"IO_SLOT"
CDS_LIB"mstr_standard";
"B \NAC \NWC"2;
"S \NAC"
BN"1"24;
%"TAP"
"6","(-3250,5800)","2","mstr_standard","I364";
;
ROOM"RISER1"
HDL_TAP"TRUE"
BODY_TYPE"PLUMBING"
BOM_COST"IO_SLOT"
CDS_LIB"mstr_standard";
"B \NAC \NWC"2;
"S \NAC"
BN"0"25;
%"TAP"
"6","(-3250,5600)","2","standard","I365";
;
ROOM"RISER1"
HDL_TAP"TRUE"
BODY_TYPE"PLUMBING"
BOM_COST"IO_SLOT"
CDS_LIB"standard";
"B \NAC \NWC"2;
"S \NAC"
BN"2"123;
%"TAP"
"6","(-3100,5450)","2","standard","I366";
;
ROOM"RISER1"
HDL_TAP"TRUE"
BODY_TYPE"PLUMBING"
BOM_COST"IO_SLOT"
CDS_LIB"standard";
"B \NAC \NWC"1;
"S \NAC"
BN"3"34;
%"TAP"
"6","(-3100,5350)","2","standard","I367";
;
ROOM"RISER1"
HDL_TAP"TRUE"
BODY_TYPE"PLUMBING"
BOM_COST"IO_SLOT"
CDS_LIB"standard";
"B \NAC \NWC"1;
"S \NAC"
BN"4"103;
%"TAP"
"6","(-3100,5150)","2","standard","I368";
;
ROOM"RISER1"
HDL_TAP"TRUE"
BODY_TYPE"PLUMBING"
BOM_COST"IO_SLOT"
CDS_LIB"standard";
"B \NAC \NWC"1;
"S \NAC"
BN"6"32;
%"TAP"
"6","(-3100,5250)","2","standard","I369";
;
ROOM"RISER1"
HDL_TAP"TRUE"
BODY_TYPE"PLUMBING"
BOM_COST"IO_SLOT"
CDS_LIB"standard";
"B \NAC \NWC"1;
"S \NAC"
BN"5"33;
%"TAP"
"6","(-3100,5050)","2","standard","I370";
;
ROOM"RISER1"
HDL_TAP"TRUE"
BODY_TYPE"PLUMBING"
BOM_COST"IO_SLOT"
CDS_LIB"standard";
"B \NAC \NWC"1;
"S \NAC"
BN"7"31;
%"TAP"
"6","(-3250,5300)","2","standard","I371";
;
ROOM"RISER1"
HDL_TAP"TRUE"
BODY_TYPE"PLUMBING"
BOM_COST"IO_SLOT"
CDS_LIB"standard";
"B \NAC \NWC"2;
"S \NAC"
BN"5"35;
%"TAP"
"6","(-3250,5400)","2","standard","I372";
;
ROOM"RISER1"
HDL_TAP"TRUE"
BODY_TYPE"PLUMBING"
BOM_COST"IO_SLOT"
CDS_LIB"standard";
"B \NAC \NWC"2;
"S \NAC"
BN"4"125;
%"TAP"
"6","(-3250,5500)","2","standard","I373";
;
ROOM"RISER1"
HDL_TAP"TRUE"
BODY_TYPE"PLUMBING"
BOM_COST"IO_SLOT"
CDS_LIB"standard";
"B \NAC \NWC"2;
"S \NAC"
BN"3"126;
%"TAP"
"6","(-3250,5100)","2","standard","I374";
;
ROOM"RISER1"
HDL_TAP"TRUE"
BODY_TYPE"PLUMBING"
BOM_COST"IO_SLOT"
CDS_LIB"standard";
"B \NAC \NWC"2;
"S \NAC"
BN"7"37;
%"TAP"
"6","(-3250,5200)","2","standard","I375";
;
ROOM"RISER1"
HDL_TAP"TRUE"
BODY_TYPE"PLUMBING"
BOM_COST"IO_SLOT"
CDS_LIB"standard";
"B \NAC \NWC"2;
"S \NAC"
BN"6"36;
%"TAP"
"6","(-3100,4950)","2","standard","I376";
;
ROOM"RISER1"
HDL_TAP"TRUE"
BODY_TYPE"PLUMBING"
BOM_COST"IO_SLOT"
CDS_LIB"standard";
"B \NAC \NWC"1;
"S \NAC"
BN"8"29;
%"TAP"
"6","(-3100,4850)","2","standard","I377";
;
ROOM"RISER1"
HDL_TAP"TRUE"
BODY_TYPE"PLUMBING"
BOM_COST"IO_SLOT"
CDS_LIB"standard";
"B \NAC \NWC"1;
"S \NAC"
BN"9"26;
%"TAP"
"6","(-3100,4650)","2","standard","I378";
;
ROOM"RISER1"
HDL_TAP"TRUE"
BODY_TYPE"PLUMBING"
BOM_COST"IO_SLOT"
CDS_LIB"standard";
"B \NAC \NWC"1;
"S \NAC"
BN"11"38;
%"TAP"
"6","(-3100,4750)","2","standard","I379";
;
ROOM"RISER1"
HDL_TAP"TRUE"
BODY_TYPE"PLUMBING"
BOM_COST"IO_SLOT"
CDS_LIB"standard";
"B \NAC \NWC"1;
"S \NAC"
BN"10"41;
%"TAP"
"6","(-3100,4550)","2","standard","I380";
;
ROOM"RISER1"
HDL_TAP"TRUE"
BODY_TYPE"PLUMBING"
BOM_COST"IO_SLOT"
CDS_LIB"standard";
"B \NAC \NWC"1;
"S \NAC"
BN"12"136;
%"TAP"
"6","(-3250,4800)","2","standard","I381";
;
ROOM"RISER1"
HDL_TAP"TRUE"
BODY_TYPE"PLUMBING"
BOM_COST"IO_SLOT"
CDS_LIB"standard";
"B \NAC \NWC"2;
"S \NAC"
BN"10"27;
%"TAP"
"6","(-3250,4900)","2","standard","I382";
;
ROOM"RISER1"
HDL_TAP"TRUE"
BODY_TYPE"PLUMBING"
BOM_COST"IO_SLOT"
CDS_LIB"standard";
"B \NAC \NWC"2;
"S \NAC"
BN"9"28;
%"TAP"
"6","(-3250,5000)","2","standard","I383";
;
ROOM"RISER1"
HDL_TAP"TRUE"
BODY_TYPE"PLUMBING"
BOM_COST"IO_SLOT"
CDS_LIB"standard";
"B \NAC \NWC"2;
"S \NAC"
BN"8"30;
%"TAP"
"6","(-3250,4500)","2","standard","I384";
;
ROOM"RISER1"
HDL_TAP"TRUE"
BODY_TYPE"PLUMBING"
BOM_COST"IO_SLOT"
CDS_LIB"standard";
"B \NAC \NWC"2;
"S \NAC"
BN"13"39;
%"TAP"
"6","(-3250,4700)","2","standard","I385";
;
ROOM"RISER1"
HDL_TAP"TRUE"
BODY_TYPE"PLUMBING"
BOM_COST"IO_SLOT"
CDS_LIB"standard";
"B \NAC \NWC"2;
"S \NAC"
BN"11"42;
%"TAP"
"6","(-3250,4600)","2","standard","I386";
;
ROOM"RISER1"
HDL_TAP"TRUE"
BODY_TYPE"PLUMBING"
BOM_COST"IO_SLOT"
CDS_LIB"standard";
"B \NAC \NWC"2;
"S \NAC"
BN"12"128;
%"TAP"
"6","(-3100,4450)","2","standard","I387";
;
ROOM"RISER1"
HDL_TAP"TRUE"
BODY_TYPE"PLUMBING"
BOM_COST"IO_SLOT"
CDS_LIB"standard";
"B \NAC \NWC"1;
"S \NAC"
BN"13"134;
%"TAP"
"6","(-3100,4250)","2","standard","I388";
;
ROOM"RISER1"
HDL_TAP"TRUE"
BODY_TYPE"PLUMBING"
BOM_COST"IO_SLOT"
CDS_LIB"standard";
"B \NAC \NWC"1;
"S \NAC"
BN"15"129;
%"TAP"
"6","(-3100,4350)","2","standard","I389";
;
ROOM"RISER1"
HDL_TAP"TRUE"
BODY_TYPE"PLUMBING"
BOM_COST"IO_SLOT"
CDS_LIB"standard";
"B \NAC \NWC"1;
"S \NAC"
BN"14"40;
%"TAP"
"6","(-3250,4400)","2","standard","I390";
;
ROOM"RISER1"
HDL_TAP"TRUE"
BODY_TYPE"PLUMBING"
BOM_COST"IO_SLOT"
CDS_LIB"standard";
"B \NAC \NWC"2;
"S \NAC"
BN"14"133;
%"TAP"
"6","(-3250,4300)","2","standard","I391";
;
ROOM"RISER1"
HDL_TAP"TRUE"
BODY_TYPE"PLUMBING"
BOM_COST"IO_SLOT"
CDS_LIB"standard";
"B \NAC \NWC"2;
"S \NAC"
BN"15"130;
END.
